# S9S_MB_2U (Grand Teton) — schematic netlist excerpt (pin names and nets, part order shuffled) for the footprints in the layout excerpt that follows; sources: Cadence DE-HDL packaged netlist, KiCad conversion of 03242023_DA0F0TMBIJ0_F0T_Motherboard_J_brd_V01_OCP.brd

J14  SCONN288_ADR50017P087CC  SCONN288_ADR50017-P087CC IO  pkg DDR288S_1-1VXB  page 95
  VIN_BULK0  = P12V_S3_AUX_CPU0_NVDIMM
  RFU0  = TP_CHG_CPU0_DIMM2_FRU_0
  VIN_MGMT  = P3V3_AUX
  HSCL  = I3C_SPD_DDREFGH_CPU0_LVC1_SCL_5
  HSDA  = I3C_SPD_DDREFGH_CPU0_LVC1_SDA
  VSS0  = GND
  DQ0_A  = M_G_CPU0_SA_DQ<0>
  VSS1  = GND
  DQ1_A  = M_G_CPU0_SA_DQ<1>
  VSS2  = GND
  DQS0_A_T  = M_G_CPU0_SA_DQS_DP<0>
  DQS0_A_C  = M_G_CPU0_SA_DQS_DN<0>
  VSS3  = GND
  DQ4_A  = M_G_CPU0_SA_DQ<4>
  VSS4  = GND
  DQ5_A  = M_G_CPU0_SA_DQ<5>
  VSS5  = GND
  DQ8_A  = M_G_CPU0_SA_DQ<8>
  VSS6  = GND
  DQ9_A  = M_G_CPU0_SA_DQ<9>
  VSS7  = GND
  DQS1_A_T  = M_G_CPU0_SA_DQS_DP<1>
  DQS1_A_C  = M_G_CPU0_SA_DQS_DN<1>
  VSS8  = GND
  DQ12_A  = M_G_CPU0_SA_DQ<12>
  VSS9  = GND
  DQ13_A  = M_G_CPU0_SA_DQ<13>
  VSS10  = GND
  DQ16_A  = M_G_CPU0_SA_DQ<16>
  VSS11  = GND
  DQ17_A  = M_G_CPU0_SA_DQ<17>
  VSS12  = GND
  DQS2_A_T  = M_G_CPU0_SA_DQS_DP<2>
  DQS2_A_C  = M_G_CPU0_SA_DQS_DN<2>
  VSS13  = GND
  DQ20_A  = M_G_CPU0_SA_DQ<20>
  VSS14  = GND
  DQ21_A  = M_G_CPU0_SA_DQ<21>
  VSS15  = GND
  DQ24_A  = M_G_CPU0_SA_DQ<24>
  VSS16  = GND
  DQ25_A  = M_G_CPU0_SA_DQ<25>
  VSS17  = GND
  DQS3_A_T  = M_G_CPU0_SA_DQS_DP<3>
  DQS3_A_C  = M_G_CPU0_SA_DQS_DN<3>
  VSS18  = GND
  DQ28_A  = M_G_CPU0_SA_DQ<28>
  VSS19  = GND
  DQ29_A  = M_G_CPU0_SA_DQ<29>
  VSS20  = GND
  CB0_A  = M_G_CPU0_SA_CB<0>
  VSS21  = GND
  CB1_A  = M_G_CPU0_SA_CB<1>
  VSS22  = GND
  DQS4_A_T  = M_G_CPU0_SA_DQS_DP<4>
  DQS4_A_C  = M_G_CPU0_SA_DQS_DN<4>
  VSS23  = GND
  CB4_A  = M_G_CPU0_SA_CB<4>
  VSS24  = GND
  CB5_A  = M_G_CPU0_SA_CB<5>
  VSS25  = GND
  ALERT_N  = M_G_CPU0_ALERT_N
  VSS26  = GND
  CS0_A_N  = M_G_CPU0_SA_CS_N<2>
  VSS27  = GND
  CA0_A  = M_G_CPU0_SA_CA<0>
  VSS28  = GND
  CA2_A  = M_G_CPU0_SA_CA<2>
  VSS29  = GND
  CA4_A  = M_G_CPU0_SA_CA<4>
  VSS30  = GND
  CA6_A  = M_G_CPU0_SA_CA<6>
  VSS31  = GND
  PAR_A  = M_G_CPU0_SA_PAR
  VSS32  = GND
  CA0_B  = M_G_CPU0_SB_CA<0>
  VSS33  = GND
  CA2_B  = M_G_CPU0_SB_CA<2>
  VSS34  = GND
  CA4_B  = M_G_CPU0_SB_CA<4>
  VSS35  = GND
  CA6_B  = M_G_CPU0_SB_CA<6>
  VSS36  = GND
  CS0_B_N  = M_G_CPU0_SB_CS_N<2>
  VSS37  = GND
  \lbd||rsp_a_n\  = M_G_CPU0_SA_RSP<1>
  \lbs||rsp_b_n\  = M_G_CPU0_SB_RSP<1>
  VSS38  = GND
  CB4_B  = M_G_CPU0_SB_CB<4>
  VSS39  = GND
  CB5_B  = M_G_CPU0_SB_CB<5>
  VSS40  = GND
  \dqs9_b_t||tdqs9_b_t||dbi4_b_n\  = M_G_CPU0_SB_DQS_DP<9>
  \dqs9_b_c||tdqs9_b_c\  = M_G_CPU0_SB_DQS_DN<9>
  VSS41  = GND
  CB0_B  = M_G_CPU0_SB_CB<0>
  VSS42  = GND
  CB1_B  = M_G_CPU0_SB_CB<1>
  VSS43  = GND
  DQ0_B  = M_G_CPU0_SB_DQ<0>
  VSS44  = GND
  DQ1_B  = M_G_CPU0_SB_DQ<1>
  VSS45  = GND
  DQS0_B_T  = M_G_CPU0_SB_DQS_DP<0>
  DQS0_B_C  = M_G_CPU0_SB_DQS_DN<0>
  VSS46  = GND
  DQ4_B  = M_G_CPU0_SB_DQ<4>
  VSS47  = GND
  DQ5_B  = M_G_CPU0_SB_DQ<5>
  VSS48  = GND
  DQ8_B  = M_G_CPU0_SB_DQ<8>
  VSS49  = GND
  DQ9_B  = M_G_CPU0_SB_DQ<9>
  VSS50  = GND
  DQS1_B_T  = M_G_CPU0_SB_DQS_DP<1>
  DQS1_B_C  = M_G_CPU0_SB_DQS_DN<1>
  VSS51  = GND
  DQ12_B  = M_G_CPU0_SB_DQ<12>
  VSS52  = GND
  DQ13_B  = M_G_CPU0_SB_DQ<13>
  VSS53  = GND
  DQ16_B  = M_G_CPU0_SB_DQ<16>
  VSS54  = GND
  DQ17_B  = M_G_CPU0_SB_DQ<17>
  VSS55  = GND
  DQS2_B_T  = M_G_CPU0_SB_DQS_DP<2>
  DQS2_B_C  = M_G_CPU0_SB_DQS_DN<2>
  VSS56  = GND
  DQ20_B  = M_G_CPU0_SB_DQ<20>
  VSS57  = GND
  DQ21_B  = M_G_CPU0_SB_DQ<21>
  VSS58  = GND
  DQ24_B  = M_G_CPU0_SB_DQ<24>
  VSS59  = GND
  DQ25_B  = M_G_CPU0_SB_DQ<25>
  VSS60  = GND
  DQS3_B_T  = M_G_CPU0_SB_DQS_DP<3>
  DQS3_B_C  = M_G_CPU0_SB_DQS_DN<3>
  VSS61  = GND
  DQ28_B  = M_G_CPU0_SB_DQ<28>
  VSS62  = GND
  DQ29_B  = M_G_CPU0_SB_DQ<29>
  VSS63  = GND
  RFU1  = TP_CHG_CPU0_DIMM2_FRU_1
  VIN_BULK1  = P12V_S3_AUX_CPU0_NVDIMM
  VIN_BULK2  = P12V_S3_AUX_CPU0_NVDIMM
  \pwr_good||fail_n\  = PWRGD_CHG_CPU0_DIMM2
  HSA  = PD_CHG_CPU0_DIMM2_SAA
  RFU2  = TP_CHG_CPU0_DIMM2_FRU_2
  RFU3  = TP_CHG_CPU0_DIMM2_FRU_3
  VSS64  = GND
  DQ2_A  = M_G_CPU0_SA_DQ<2>
  VSS65  = GND
  DQ3_A  = M_G_CPU0_SA_DQ<3>
  VSS66  = GND
  \dqs5_a_c||tdqs5_a_c||dqs5_a_t||tdqs5_a_t\  = M_G_CPU0_SA_DQS_DN<5>
  \dqs5_a_t||tdqs5_a_t\  = M_G_CPU0_SA_DQS_DP<5>
  VSS67  = GND
  DQ6_A  = M_G_CPU0_SA_DQ<6>
  VSS68  = GND
  DQ7_A  = M_G_CPU0_SA_DQ<7>
  VSS69  = GND
  DQ10_A  = M_G_CPU0_SA_DQ<10>
  VSS70  = GND
  DQ11_A  = M_G_CPU0_SA_DQ<11>
  VSS71  = GND
  \dqs6_a_c||tdqs6_a_c||dqs6_a_t||tdqs6_a_t\  = M_G_CPU0_SA_DQS_DN<6>
  \dqs6_a_t||tdqs6_a_t\  = M_G_CPU0_SA_DQS_DP<6>
  VSS72  = GND
  DQ14_A  = M_G_CPU0_SA_DQ<14>
  VSS73  = GND
  DQ15_A  = M_G_CPU0_SA_DQ<15>
  VSS74  = GND
  DQ18_A  = M_G_CPU0_SA_DQ<18>
  VSS75  = GND
  DQ19_A  = M_G_CPU0_SA_DQ<19>
  VSS76  = GND
  \dqs7_a_c||tdqs7_a_c\  = M_G_CPU0_SA_DQS_DN<7>
  \dqs7_a_t||tdqs7_a_t\  = M_G_CPU0_SA_DQS_DP<7>
  VSS77  = GND
  DQ22_A  = M_G_CPU0_SA_DQ<22>
  VSS78  = GND
  DQ23_A  = M_G_CPU0_SA_DQ<23>
  VSS79  = GND
  DQ26_A  = M_G_CPU0_SA_DQ<26>
  VSS80  = GND
  DQ27_A  = M_G_CPU0_SA_DQ<27>
  VSS81  = GND
  \dqs8_a_c||tdqs8_a_c\  = M_G_CPU0_SA_DQS_DN<8>
  \dqs8_a_t||tdqs8_a_t\  = M_G_CPU0_SA_DQS_DP<8>
  VSS82  = GND
  DQ30_A  = M_G_CPU0_SA_DQ<30>
  VSS83  = GND
  DQ31_A  = M_G_CPU0_SA_DQ<31>
  VSS84  = GND
  CB2_A  = M_G_CPU0_SA_CB<2>
  VSS85  = GND
  CB3_A  = M_G_CPU0_SA_CB<3>
  VSS86  = GND
  \dqs9_a_c||tdqs9_a_c\  = M_G_CPU0_SA_DQS_DN<9>
  \dqs9_a_t||tdqs9_a_t\  = M_G_CPU0_SA_DQS_DP<9>
  VSS87  = GND
  CB6_A  = M_G_CPU0_SA_CB<6>
  VSS88  = GND
  CB7_A  = M_G_CPU0_SA_CB<7>
  VSS89  = GND
  RESET_N  = RST_M_GH_CPU0_FPGA_N
  VSS90  = GND
  CS1_A_N  = M_G_CPU0_SA_CS_N<3>
  VSS91  = GND
  CA1_A  = M_G_CPU0_SA_CA<1>
  VSS92  = GND
  CA3_A  = M_G_CPU0_SA_CA<3>
  VSS93  = GND
  CA5_A  = M_G_CPU0_SA_CA<5>
  VSS94  = GND
  CK_T  = M_G_CPU0_CLK_DP<1>
  CK_C  = M_G_CPU0_CLK_DN<1>
  VSS95  = GND
  RFU4  = TP_CHG_CPU0_DIMM2_FRU_4
  CA1_B  = M_G_CPU0_SB_CA<1>
  VSS96  = GND
  CA3_B  = M_G_CPU0_SB_CA<3>
  VSS97  = GND
  CA5_B  = M_G_CPU0_SB_CA<5>
  VSS98  = GND
  PAR_B  = M_G_CPU0_SB_PAR
  VSS99  = GND
  CS1_B_N  = M_G_CPU0_SB_CS_N<3>
  VSS100  = GND
  RFU5  = TP_CHG_CPU0_DIMM2_FRU_5
  RFU6  = TP_CHG_CPU0_DIMM2_FRU_6
  VSS101  = GND
  CB6_B  = M_G_CPU0_SB_CB<6>
  VSS102  = GND
  CB7_B  = M_G_CPU0_SB_CB<7>
  VSS103  = GND
  DQS4_B_C  = M_G_CPU0_SB_DQS_DN<4>
  DQS4_B_T  = M_G_CPU0_SB_DQS_DP<4>
  VSS104  = GND
  CB2_B  = M_G_CPU0_SB_CB<2>
  VSS105  = GND
  CB3_B  = M_G_CPU0_SB_CB<3>
  VSS106  = GND
  DQ2_B  = M_G_CPU0_SB_DQ<2>
  VSS107  = GND
  DQ3_B  = M_G_CPU0_SB_DQ<3>
  VSS108  = GND
  \dqs5_b_c||tdqs5_b_c\  = M_G_CPU0_SB_DQS_DN<5>
  \dqs5_b_t||tdqs5_b_t\  = M_G_CPU0_SB_DQS_DP<5>
  VSS109  = GND
  DQ6_B  = M_G_CPU0_SB_DQ<6>
  VSS110  = GND
  DQ7_B  = M_G_CPU0_SB_DQ<7>
  VSS111  = GND
  DQ10_B  = M_G_CPU0_SB_DQ<10>
  VSS112  = GND
  DQ11_B  = M_G_CPU0_SB_DQ<11>
  VSS113  = GND
  \dqs6_b_c||tdqs6_b_c\  = M_G_CPU0_SB_DQS_DN<6>
  \dqs6_b_t||tdqs6_b_t\  = M_G_CPU0_SB_DQS_DP<6>
  VSS114  = GND
  DQ14_B  = M_G_CPU0_SB_DQ<14>
  VSS115  = GND
  DQ15_B  = M_G_CPU0_SB_DQ<15>
  VSS116  = GND
  DQ18_B  = M_G_CPU0_SB_DQ<18>
  VSS117  = GND
  DQ19_B  = M_G_CPU0_SB_DQ<19>
  VSS118  = GND
  \dqs7_b_c||tdqs7_b_c\  = M_G_CPU0_SB_DQS_DN<7>
  \dqs7_b_t||tdqs7_b_t\  = M_G_CPU0_SB_DQS_DP<7>
  VSS119  = GND
  DQ22_B  = M_G_CPU0_SB_DQ<22>
  VSS120  = GND
  DQ23_B  = M_G_CPU0_SB_DQ<23>
  VSS121  = GND
  DQ26_B  = M_G_CPU0_SB_DQ<26>
  VSS122  = GND
  DQ27_B  = M_G_CPU0_SB_DQ<27>
  VSS123  = GND
  \dqs8_b_c||tdqs8_b_c\  = M_G_CPU0_SB_DQS_DN<8>
  \dqs8_b_t||tdqs8_b_t\  = M_G_CPU0_SB_DQS_DP<8>
  VSS124  = GND
  DQ30_B  = M_G_CPU0_SB_DQ<30>
  VSS125  = GND
  DQ31_B  = M_G_CPU0_SB_DQ<31>
  VSS126  = GND
  G1  = GND
  G2  = GND
  G3  = GND

(kicad_pcb
	(version 20260206)
	(generator "pcbnew")
	(generator_version "10.0")
	(general
		(thickness 1.6)
		(legacy_teardrops no)
	)
	(paper "A4")
	(title_block
		(title "03242023_DA0F0TMBIJ0_F0T_Motherboard_J_brd_V01_OCP.brd")
		(comment 1 "Grand Teton / footprint 3833 of 6105 (J14), pads 183-228 of 291")
	)
	(layers
		(0 "F.Cu" signal "TOP")
		(4 "In1.Cu" signal "GND")
		(6 "In2.Cu" signal "IN1")
		(8 "In3.Cu" signal "GND1")
		(10 "In4.Cu" signal "IN2")
		(12 "In5.Cu" signal "GND2")
		(14 "In6.Cu" signal "IN3")
		(16 "In7.Cu" signal "GND3")
		(18 "In8.Cu" signal "VCC")
		(20 "In9.Cu" signal "VCC1")
		(22 "In10.Cu" signal "GND4")
		(24 "In11.Cu" signal "IN4")
		(26 "In12.Cu" signal "GND5")
		(28 "In13.Cu" signal "IN5")
		(30 "In14.Cu" signal "GND6")
		(32 "In15.Cu" signal "IN6")
		(34 "In16.Cu" signal "GND7")
		(2 "B.Cu" signal "BOTTOM")
		(9 "F.Adhes" user "F.Adhesive")
		(11 "B.Adhes" user "B.Adhesive")
		(13 "F.Paste" user "Package Geometry/Pastemask Top")
		(15 "B.Paste" user "Package Geometry/Pastemask Bottom")
		(5 "F.SilkS" user "Ref Des/Silkscreen Top")
		(7 "B.SilkS" user "Ref Des/Silkscreen Bottom")
		(1 "F.Mask" user "Board Geometry/Soldermask Top")
		(3 "B.Mask" user "Board Geometry/Soldermask Bottom")
		(17 "Dwgs.User" user "User.Drawings")
		(19 "Cmts.User" user "User.Comments")
		(21 "Eco1.User" user "User.Eco1")
		(23 "Eco2.User" user "User.Eco2")
		(25 "Edge.Cuts" user "Board Geometry/Outline")
		(27 "Margin" user)
		(31 "F.CrtYd" user "Package Geometry/Place Bound Top")
		(29 "B.CrtYd" user "Package Geometry/Place Bound Bottom")
		(35 "F.Fab" user "Ref Des/Assembly Top")
		(33 "B.Fab" user "Ref Des/Assembly Bottom")
	)
	(footprint ""
		(layer "F.Cu")
		(at 438.978548 -258.091686)
		(property "Reference" "J14"
			(at -3.683 -81.702148 0)
			(unlocked yes)
			(layer "F.SilkS")
			(effects
				(font
					(size 0.7874 0.5842)
					(thickness 0.1524)
				)
				(justify left)
			)
		)
		(property "Value" ""
			(at 0 0 0)
			(layer "F.Fab")
			(effects
				(font
					(size 1.27 1.27)
				)
			)
		)
		(duplicate_pad_numbers_are_jumpers no)
		(pad "183" smd rect
			(at 2.050034 -31.025084 270)
			(size 0.519938 1.4986)
			(layers "F.Cu" "F.Mask" "F.Paste")
			(net "M_G_CPU0_SA_DQ<23>")
		)
		(pad "184" smd rect
			(at 2.050034 -30.174946 270)
			(size 0.519938 1.4986)
			(layers "F.Cu" "F.Mask" "F.Paste")
			(net "GND")
		)
		(pad "185" smd rect
			(at 2.050034 -29.325062 270)
			(size 0.519938 1.4986)
			(layers "F.Cu" "F.Mask" "F.Paste")
			(net "M_G_CPU0_SA_DQ<26>")
		)
		(pad "186" smd rect
			(at 2.050034 -28.474924 270)
			(size 0.519938 1.4986)
			(layers "F.Cu" "F.Mask" "F.Paste")
			(net "GND")
		)
		(pad "187" smd rect
			(at 2.050034 -27.62504 270)
			(size 0.519938 1.4986)
			(layers "F.Cu" "F.Mask" "F.Paste")
			(net "M_G_CPU0_SA_DQ<27>")
		)
		(pad "188" smd rect
			(at 2.050034 -26.774902 270)
			(size 0.519938 1.4986)
			(layers "F.Cu" "F.Mask" "F.Paste")
			(net "GND")
		)
		(pad "189" smd rect
			(at 2.050034 -25.925018 270)
			(size 0.519938 1.4986)
			(layers "F.Cu" "F.Mask" "F.Paste")
			(net "M_G_CPU0_SA_DQS_DN<8>")
		)
		(pad "190" smd rect
			(at 2.050034 -25.07488 270)
			(size 0.519938 1.4986)
			(layers "F.Cu" "F.Mask" "F.Paste")
			(net "M_G_CPU0_SA_DQS_DP<8>")
		)
		(pad "191" smd rect
			(at 2.050034 -24.224996 270)
			(size 0.519938 1.4986)
			(layers "F.Cu" "F.Mask" "F.Paste")
			(net "GND")
		)
		(pad "192" smd rect
			(at 2.050034 -23.375112 270)
			(size 0.519938 1.4986)
			(layers "F.Cu" "F.Mask" "F.Paste")
			(net "M_G_CPU0_SA_DQ<30>")
		)
		(pad "193" smd rect
			(at 2.050034 -22.524974 270)
			(size 0.519938 1.4986)
			(layers "F.Cu" "F.Mask" "F.Paste")
			(net "GND")
		)
		(pad "194" smd rect
			(at 2.050034 -21.67509 270)
			(size 0.519938 1.4986)
			(layers "F.Cu" "F.Mask" "F.Paste")
			(net "M_G_CPU0_SA_DQ<31>")
		)
		(pad "195" smd rect
			(at 2.050034 -20.824952 270)
			(size 0.519938 1.4986)
			(layers "F.Cu" "F.Mask" "F.Paste")
			(net "GND")
		)
		(pad "196" smd rect
			(at 2.050034 -19.975068 270)
			(size 0.519938 1.4986)
			(layers "F.Cu" "F.Mask" "F.Paste")
			(net "M_G_CPU0_SA_CB<2>")
		)
		(pad "197" smd rect
			(at 2.050034 -19.12493 270)
			(size 0.519938 1.4986)
			(layers "F.Cu" "F.Mask" "F.Paste")
			(net "GND")
		)
		(pad "198" smd rect
			(at 2.050034 -18.275046 270)
			(size 0.519938 1.4986)
			(layers "F.Cu" "F.Mask" "F.Paste")
			(net "M_G_CPU0_SA_CB<3>")
		)
		(pad "199" smd rect
			(at 2.050034 -17.424908 270)
			(size 0.519938 1.4986)
			(layers "F.Cu" "F.Mask" "F.Paste")
			(net "GND")
		)
		(pad "200" smd rect
			(at 2.050034 -16.575024 270)
			(size 0.519938 1.4986)
			(layers "F.Cu" "F.Mask" "F.Paste")
			(net "M_G_CPU0_SA_DQS_DN<9>")
		)
		(pad "201" smd rect
			(at 2.050034 -15.724886 270)
			(size 0.519938 1.4986)
			(layers "F.Cu" "F.Mask" "F.Paste")
			(net "M_G_CPU0_SA_DQS_DP<9>")
		)
		(pad "202" smd rect
			(at 2.050034 -14.875002 270)
			(size 0.519938 1.4986)
			(layers "F.Cu" "F.Mask" "F.Paste")
			(net "GND")
		)
		(pad "203" smd rect
			(at 2.050034 -14.025118 270)
			(size 0.519938 1.4986)
			(layers "F.Cu" "F.Mask" "F.Paste")
			(net "M_G_CPU0_SA_CB<6>")
		)
		(pad "204" smd rect
			(at 2.050034 -13.17498 270)
			(size 0.519938 1.4986)
			(layers "F.Cu" "F.Mask" "F.Paste")
			(net "GND")
		)
		(pad "205" smd rect
			(at 2.050034 -12.325096 270)
			(size 0.519938 1.4986)
			(layers "F.Cu" "F.Mask" "F.Paste")
			(net "M_G_CPU0_SA_CB<7>")
		)
		(pad "206" smd rect
			(at 2.050034 -11.474958 270)
			(size 0.519938 1.4986)
			(layers "F.Cu" "F.Mask" "F.Paste")
			(net "GND")
		)
		(pad "207" smd rect
			(at 2.050034 -10.625074 270)
			(size 0.519938 1.4986)
			(layers "F.Cu" "F.Mask" "F.Paste")
			(net "RST_M_GH_CPU0_FPGA_N")
		)
		(pad "208" smd rect
			(at 2.050034 -9.774936 270)
			(size 0.519938 1.4986)
			(layers "F.Cu" "F.Mask" "F.Paste")
			(net "GND")
		)
		(pad "209" smd rect
			(at 2.050034 -8.925052 270)
			(size 0.519938 1.4986)
			(layers "F.Cu" "F.Mask" "F.Paste")
			(net "M_G_CPU0_SA_CS_N<3>")
		)
		(pad "210" smd rect
			(at 2.050034 -8.074914 270)
			(size 0.519938 1.4986)
			(layers "F.Cu" "F.Mask" "F.Paste")
			(net "GND")
		)
		(pad "211" smd rect
			(at 2.050034 -7.22503 270)
			(size 0.519938 1.4986)
			(layers "F.Cu" "F.Mask" "F.Paste")
			(net "M_G_CPU0_SA_CA<1>")
		)
		(pad "212" smd rect
			(at 2.050034 -6.374892 270)
			(size 0.519938 1.4986)
			(layers "F.Cu" "F.Mask" "F.Paste")
			(net "GND")
		)
		(pad "213" smd rect
			(at 2.050034 -5.525008 270)
			(size 0.519938 1.4986)
			(layers "F.Cu" "F.Mask" "F.Paste")
			(net "M_G_CPU0_SA_CA<3>")
		)
		(pad "214" smd rect
			(at 2.050034 -4.675124 270)
			(size 0.519938 1.4986)
			(layers "F.Cu" "F.Mask" "F.Paste")
			(net "GND")
		)
		(pad "215" smd rect
			(at 2.050034 -3.824986 270)
			(size 0.519938 1.4986)
			(layers "F.Cu" "F.Mask" "F.Paste")
			(net "M_G_CPU0_SA_CA<5>")
		)
		(pad "216" smd rect
			(at 2.050034 -2.975102 270)
			(size 0.519938 1.4986)
			(layers "F.Cu" "F.Mask" "F.Paste")
			(net "GND")
		)
		(pad "217" smd rect
			(at 2.050034 -2.124964 270)
			(size 0.519938 1.4986)
			(layers "F.Cu" "F.Mask" "F.Paste")
			(net "M_G_CPU0_CLK_DP<1>")
		)
		(pad "218" smd rect
			(at 2.050034 -1.27508 270)
			(size 0.519938 1.4986)
			(layers "F.Cu" "F.Mask" "F.Paste")
			(net "M_G_CPU0_CLK_DN<1>")
		)
		(pad "219" smd rect
			(at 2.050034 -0.424942 270)
			(size 0.519938 1.4986)
			(layers "F.Cu" "F.Mask" "F.Paste")
			(net "GND")
		)
		(pad "220" smd rect
			(at 2.050034 5.525008 270)
			(size 0.519938 1.4986)
			(layers "F.Cu" "F.Mask" "F.Paste")
			(net "TP_CHG_CPU0_DIMM2_FRU_4")
		)
		(pad "221" smd rect
			(at 2.050034 6.374892 270)
			(size 0.519938 1.4986)
			(layers "F.Cu" "F.Mask" "F.Paste")
			(net "M_G_CPU0_SB_CA<1>")
		)
		(pad "222" smd rect
			(at 2.050034 7.22503 270)
			(size 0.519938 1.4986)
			(layers "F.Cu" "F.Mask" "F.Paste")
			(net "GND")
		)
		(pad "223" smd rect
			(at 2.050034 8.074914 270)
			(size 0.519938 1.4986)
			(layers "F.Cu" "F.Mask" "F.Paste")
			(net "M_G_CPU0_SB_CA<3>")
		)
		(pad "224" smd rect
			(at 2.050034 8.925052 270)
			(size 0.519938 1.4986)
			(layers "F.Cu" "F.Mask" "F.Paste")
			(net "GND")
		)
		(pad "225" smd rect
			(at 2.050034 9.774936 270)
			(size 0.519938 1.4986)
			(layers "F.Cu" "F.Mask" "F.Paste")
			(net "M_G_CPU0_SB_CA<5>")
		)
		(pad "226" smd rect
			(at 2.050034 10.625074 270)
			(size 0.519938 1.4986)
			(layers "F.Cu" "F.Mask" "F.Paste")
			(net "GND")
		)
		(pad "227" smd rect
			(at 2.050034 11.474958 270)
			(size 0.519938 1.4986)
			(layers "F.Cu" "F.Mask" "F.Paste")
			(net "M_G_CPU0_SB_PAR")
		)
		(pad "228" smd rect
			(at 2.050034 12.325096 270)
			(size 0.519938 1.4986)
			(layers "F.Cu" "F.Mask" "F.Paste")
			(net "GND")
		)
	)
)
